(kicad_pcb
	(version 20260206)
	(generator "pcbnew")
	(generator_version "10.0")
	(general
		(thickness 1.6)
		(legacy_teardrops no)
	)
	(paper "A4")
	(title_block
		(title "01162023_DA0F0TEBIF0_F0T_Expander_BD_F_brd_V02_OCP.brd")
		(comment 1 "Grand Teton / footprints 5482-5488 of 9728")
	)
	(layers
		(0 "F.Cu" signal "TOP")
		(4 "In1.Cu" signal "GND")
		(6 "In2.Cu" signal "VCC")
		(8 "In3.Cu" signal "VCC1")
		(10 "In4.Cu" signal "GND1")
		(12 "In5.Cu" signal "IN1")
		(14 "In6.Cu" signal "GND2")
		(16 "In7.Cu" signal "IN2")
		(18 "In8.Cu" signal "GND3")
		(20 "In9.Cu" signal "IN3")
		(22 "In10.Cu" signal "GND4")
		(24 "In11.Cu" signal "IN4")
		(26 "In12.Cu" signal "GND5")
		(28 "In13.Cu" signal "IN5")
		(30 "In14.Cu" signal "GND6")
		(32 "In15.Cu" signal "IN6")
		(34 "In16.Cu" signal "GND7")
		(2 "B.Cu" signal "BOTTOM")
		(9 "F.Adhes" user "F.Adhesive")
		(11 "B.Adhes" user "B.Adhesive")
		(13 "F.Paste" user "Package Geometry/Pastemask Top")
		(15 "B.Paste" user "Package Geometry/Pastemask Bottom")
		(5 "F.SilkS" user "Ref Des/Silkscreen Top")
		(7 "B.SilkS" user "Ref Des/Silkscreen Bottom")
		(1 "F.Mask" user "Board Geometry/Soldermask Top")
		(3 "B.Mask" user "Board Geometry/Soldermask Bottom")
		(17 "Dwgs.User" user "User.Drawings")
		(19 "Cmts.User" user "User.Comments")
		(21 "Eco1.User" user "User.Eco1")
		(23 "Eco2.User" user "User.Eco2")
		(25 "Edge.Cuts" user "Board Geometry/Outline")
		(27 "Margin" user)
		(31 "F.CrtYd" user "Package Geometry/Place Bound Top")
		(29 "B.CrtYd" user "Package Geometry/Place Bound Bottom")
		(35 "F.Fab" user "Ref Des/Assembly Top")
		(33 "B.Fab" user "Ref Des/Assembly Bottom")
	)
	(footprint ""
		(layer "F.Cu")
		(at 226.550982 -155.998672 90)
		(property "Reference" "R4196"
			(at 0 0 90)
			(layer "F.SilkS")
			(hide yes)
			(effects
				(font
					(size 1.27 1.27)
				)
			)
		)
		(property "Value" ""
			(at 0 0 90)
			(layer "F.Fab")
			(effects
				(font
					(size 1.27 1.27)
				)
			)
		)
		(duplicate_pad_numbers_are_jumpers no)
		(fp_line
			(start 0.7874 -0.4064)
			(end 0.7874 0.4064)
			(stroke
				(width 0.1524)
				(type default)
			)
			(layer "F.SilkS")
		)
		(fp_line
			(start -0.7874 -0.4064)
			(end 0.7874 -0.4064)
			(stroke
				(width 0.1524)
				(type default)
			)
			(layer "F.SilkS")
		)
		(fp_line
			(start 0.7874 0.4064)
			(end -0.7874 0.4064)
			(stroke
				(width 0.1524)
				(type default)
			)
			(layer "F.SilkS")
		)
		(fp_line
			(start -0.7874 0.4064)
			(end -0.7874 -0.4064)
			(stroke
				(width 0.1524)
				(type default)
			)
			(layer "F.SilkS")
		)
		(fp_line
			(start -0.12065 -0.305054)
			(end -0.12065 -0.2794)
			(stroke
				(width 0.1)
				(type default)
			)
			(layer "F.Fab")
		)
		(fp_line
			(start -0.67945 -0.305054)
			(end -0.12065 -0.305054)
			(stroke
				(width 0.1)
				(type default)
			)
			(layer "F.Fab")
		)
		(fp_line
			(start 0.67945 -0.3048)
			(end 0.67945 0.3048)
			(stroke
				(width 0.1)
				(type default)
			)
			(layer "F.Fab")
		)
		(fp_line
			(start 0.12065 -0.3048)
			(end 0.67945 -0.3048)
			(stroke
				(width 0.1)
				(type default)
			)
			(layer "F.Fab")
		)
		(fp_line
			(start 0.12065 -0.2794)
			(end 0.12065 -0.3048)
			(stroke
				(width 0.1)
				(type default)
			)
			(layer "F.Fab")
		)
		(fp_line
			(start -0.12065 -0.2794)
			(end 0.12065 -0.2794)
			(stroke
				(width 0.1)
				(type default)
			)
			(layer "F.Fab")
		)
		(fp_line
			(start 0.120396 0.2794)
			(end -0.12065 0.2794)
			(stroke
				(width 0.1)
				(type default)
			)
			(layer "F.Fab")
		)
		(fp_line
			(start -0.12065 0.2794)
			(end -0.12065 0.3048)
			(stroke
				(width 0.1)
				(type default)
			)
			(layer "F.Fab")
		)
		(fp_line
			(start 0.67945 0.3048)
			(end 0.120396 0.3048)
			(stroke
				(width 0.1)
				(type default)
			)
			(layer "F.Fab")
		)
		(fp_line
			(start 0.120396 0.3048)
			(end 0.120396 0.2794)
			(stroke
				(width 0.1)
				(type default)
			)
			(layer "F.Fab")
		)
		(fp_line
			(start -0.12065 0.3048)
			(end -0.67945 0.3048)
			(stroke
				(width 0.1)
				(type default)
			)
			(layer "F.Fab")
		)
		(fp_line
			(start -0.67945 0.3048)
			(end -0.67945 -0.305054)
			(stroke
				(width 0.1)
				(type default)
			)
			(layer "F.Fab")
		)
		(pad "1" smd circle
			(at -0.40005 0 90)
			(size 0 0)
			(layers "F.Cu" "F.Mask" "F.Paste")
			(net "PEX_REF_CLK_GEN_EN_N")
		)
		(pad "2" smd circle
			(at 0.40005 0 90)
			(size 0 0)
			(layers "F.Cu" "F.Mask" "F.Paste")
			(net "P3V3")
		)
	)
	(footprint ""
		(layer "F.Cu")
		(at 293.657782 -343.952322 90)
		(property "Reference" "C2364"
			(at 0 0 90)
			(layer "F.SilkS")
			(hide yes)
			(effects
				(font
					(size 1.27 1.27)
				)
			)
		)
		(property "Value" ""
			(at 0 0 90)
			(layer "F.Fab")
			(effects
				(font
					(size 1.27 1.27)
				)
			)
		)
		(duplicate_pad_numbers_are_jumpers no)
		(fp_line
			(start 0.299974 -0.150114)
			(end 0.299974 0.150114)
			(stroke
				(width 0.1)
				(type default)
			)
			(layer "F.Fab")
		)
		(fp_line
			(start -0.299974 -0.150114)
			(end 0.299974 -0.150114)
			(stroke
				(width 0.1)
				(type default)
			)
			(layer "F.Fab")
		)
		(fp_line
			(start 0.299974 0.150114)
			(end -0.299974 0.150114)
			(stroke
				(width 0.1)
				(type default)
			)
			(layer "F.Fab")
		)
		(fp_line
			(start -0.299974 0.150114)
			(end -0.299974 -0.150114)
			(stroke
				(width 0.1)
				(type default)
			)
			(layer "F.Fab")
		)
		(pad "1" smd rect
			(at -0.2667 0 90)
			(size 0.3048 0.381)
			(layers "F.Cu" "F.Mask" "F.Paste")
			(net "P5E_PEX2_STN4_TX_DN<68>")
		)
		(pad "2" smd rect
			(at 0.2667 0 90)
			(size 0.3048 0.381)
			(layers "F.Cu" "F.Mask" "F.Paste")
			(net "P5E_PEX2_STN4_TX_C_DN<68>")
		)
	)
	(footprint ""
		(layer "F.Cu")
		(at 338.796884 -115.646454 180)
		(property "Reference" "PR7036"
			(at 0 0 180)
			(layer "F.SilkS")
			(hide yes)
			(effects
				(font
					(size 1.27 1.27)
				)
			)
		)
		(property "Value" ""
			(at 0 0 180)
			(layer "F.Fab")
			(effects
				(font
					(size 1.27 1.27)
				)
			)
		)
		(duplicate_pad_numbers_are_jumpers no)
		(fp_line
			(start 0.7874 0.4064)
			(end -0.7874 0.4064)
			(stroke
				(width 0.1524)
				(type default)
			)
			(layer "F.SilkS")
		)
		(fp_line
			(start 0.7874 -0.4064)
			(end 0.7874 0.4064)
			(stroke
				(width 0.1524)
				(type default)
			)
			(layer "F.SilkS")
		)
		(fp_line
			(start -0.7874 0.4064)
			(end -0.7874 -0.4064)
			(stroke
				(width 0.1524)
				(type default)
			)
			(layer "F.SilkS")
		)
		(fp_line
			(start -0.7874 -0.4064)
			(end 0.7874 -0.4064)
			(stroke
				(width 0.1524)
				(type default)
			)
			(layer "F.SilkS")
		)
		(fp_line
			(start 0.67945 0.3048)
			(end 0.120396 0.3048)
			(stroke
				(width 0.1)
				(type default)
			)
			(layer "F.Fab")
		)
		(fp_line
			(start 0.67945 -0.3048)
			(end 0.67945 0.3048)
			(stroke
				(width 0.1)
				(type default)
			)
			(layer "F.Fab")
		)
		(fp_line
			(start 0.12065 -0.2794)
			(end 0.12065 -0.3048)
			(stroke
				(width 0.1)
				(type default)
			)
			(layer "F.Fab")
		)
		(fp_line
			(start 0.12065 -0.3048)
			(end 0.67945 -0.3048)
			(stroke
				(width 0.1)
				(type default)
			)
			(layer "F.Fab")
		)
		(fp_line
			(start 0.120396 0.3048)
			(end 0.120396 0.2794)
			(stroke
				(width 0.1)
				(type default)
			)
			(layer "F.Fab")
		)
		(fp_line
			(start 0.120396 0.2794)
			(end -0.12065 0.2794)
			(stroke
				(width 0.1)
				(type default)
			)
			(layer "F.Fab")
		)
		(fp_line
			(start -0.12065 0.3048)
			(end -0.67945 0.3048)
			(stroke
				(width 0.1)
				(type default)
			)
			(layer "F.Fab")
		)
		(fp_line
			(start -0.12065 0.2794)
			(end -0.12065 0.3048)
			(stroke
				(width 0.1)
				(type default)
			)
			(layer "F.Fab")
		)
		(fp_line
			(start -0.12065 -0.2794)
			(end 0.12065 -0.2794)
			(stroke
				(width 0.1)
				(type default)
			)
			(layer "F.Fab")
		)
		(fp_line
			(start -0.12065 -0.305054)
			(end -0.12065 -0.2794)
			(stroke
				(width 0.1)
				(type default)
			)
			(layer "F.Fab")
		)
		(fp_line
			(start -0.67945 0.3048)
			(end -0.67945 -0.305054)
			(stroke
				(width 0.1)
				(type default)
			)
			(layer "F.Fab")
		)
		(fp_line
			(start -0.67945 -0.305054)
			(end -0.12065 -0.305054)
			(stroke
				(width 0.1)
				(type default)
			)
			(layer "F.Fab")
		)
		(pad "1" smd circle
			(at -0.40005 0 180)
			(size 0 0)
			(layers "F.Cu" "F.Mask" "F.Paste")
			(net "P12V_NIC5_CO_OV_FB")
		)
		(pad "2" smd circle
			(at 0.40005 0 180)
			(size 0 0)
			(layers "F.Cu" "F.Mask" "F.Paste")
			(net "GND")
		)
	)
	(footprint ""
		(layer "F.Cu")
		(at 376.936 -185.801)
		(property "Reference" "R4651"
			(at 0 0 0)
			(layer "F.SilkS")
			(hide yes)
			(effects
				(font
					(size 1.27 1.27)
				)
			)
		)
		(property "Value" ""
			(at 0 0 0)
			(layer "F.Fab")
			(effects
				(font
					(size 1.27 1.27)
				)
			)
		)
		(duplicate_pad_numbers_are_jumpers no)
		(fp_line
			(start -0.7874 -0.4064)
			(end 0.7874 -0.4064)
			(stroke
				(width 0.1524)
				(type default)
			)
			(layer "F.SilkS")
		)
		(fp_line
			(start -0.7874 0.4064)
			(end -0.7874 -0.4064)
			(stroke
				(width 0.1524)
				(type default)
			)
			(layer "F.SilkS")
		)
		(fp_line
			(start 0.7874 -0.4064)
			(end 0.7874 0.4064)
			(stroke
				(width 0.1524)
				(type default)
			)
			(layer "F.SilkS")
		)
		(fp_line
			(start 0.7874 0.4064)
			(end -0.7874 0.4064)
			(stroke
				(width 0.1524)
				(type default)
			)
			(layer "F.SilkS")
		)
		(fp_line
			(start -0.67945 -0.305054)
			(end -0.12065 -0.305054)
			(stroke
				(width 0.1)
				(type default)
			)
			(layer "F.Fab")
		)
		(fp_line
			(start -0.67945 0.3048)
			(end -0.67945 -0.305054)
			(stroke
				(width 0.1)
				(type default)
			)
			(layer "F.Fab")
		)
		(fp_line
			(start -0.12065 -0.305054)
			(end -0.12065 -0.2794)
			(stroke
				(width 0.1)
				(type default)
			)
			(layer "F.Fab")
		)
		(fp_line
			(start -0.12065 -0.2794)
			(end 0.12065 -0.2794)
			(stroke
				(width 0.1)
				(type default)
			)
			(layer "F.Fab")
		)
		(fp_line
			(start -0.12065 0.2794)
			(end -0.12065 0.3048)
			(stroke
				(width 0.1)
				(type default)
			)
			(layer "F.Fab")
		)
		(fp_line
			(start -0.12065 0.3048)
			(end -0.67945 0.3048)
			(stroke
				(width 0.1)
				(type default)
			)
			(layer "F.Fab")
		)
		(fp_line
			(start 0.120396 0.2794)
			(end -0.12065 0.2794)
			(stroke
				(width 0.1)
				(type default)
			)
			(layer "F.Fab")
		)
		(fp_line
			(start 0.120396 0.3048)
			(end 0.120396 0.2794)
			(stroke
				(width 0.1)
				(type default)
			)
			(layer "F.Fab")
		)
		(fp_line
			(start 0.12065 -0.3048)
			(end 0.67945 -0.3048)
			(stroke
				(width 0.1)
				(type default)
			)
			(layer "F.Fab")
		)
		(fp_line
			(start 0.12065 -0.2794)
			(end 0.12065 -0.3048)
			(stroke
				(width 0.1)
				(type default)
			)
			(layer "F.Fab")
		)
		(fp_line
			(start 0.67945 -0.3048)
			(end 0.67945 0.3048)
			(stroke
				(width 0.1)
				(type default)
			)
			(layer "F.Fab")
		)
		(fp_line
			(start 0.67945 0.3048)
			(end 0.120396 0.3048)
			(stroke
				(width 0.1)
				(type default)
			)
			(layer "F.Fab")
		)
		(pad "1" smd circle
			(at -0.40005 0)
			(size 0 0)
			(layers "F.Cu" "F.Mask" "F.Paste")
			(net "NIC1_PEX_PWR_EN")
		)
		(pad "2" smd circle
			(at 0.40005 0)
			(size 0 0)
			(layers "F.Cu" "F.Mask" "F.Paste")
			(net "NIC1_PEX_PWR_EN_R")
		)
	)
	(footprint ""
		(layer "F.Cu")
		(at 289.49396 -35.264852)
		(property "Reference" "R5695"
			(at 0 0 0)
			(layer "F.SilkS")
			(hide yes)
			(effects
				(font
					(size 1.27 1.27)
				)
			)
		)
		(property "Value" ""
			(at 0 0 0)
			(layer "F.Fab")
			(effects
				(font
					(size 1.27 1.27)
				)
			)
		)
		(duplicate_pad_numbers_are_jumpers no)
		(fp_line
			(start -0.7874 -0.4064)
			(end 0.7874 -0.4064)
			(stroke
				(width 0.1524)
				(type default)
			)
			(layer "F.SilkS")
		)
		(fp_line
			(start -0.7874 0.4064)
			(end -0.7874 -0.4064)
			(stroke
				(width 0.1524)
				(type default)
			)
			(layer "F.SilkS")
		)
		(fp_line
			(start 0.7874 -0.4064)
			(end 0.7874 0.4064)
			(stroke
				(width 0.1524)
				(type default)
			)
			(layer "F.SilkS")
		)
		(fp_line
			(start 0.7874 0.4064)
			(end -0.7874 0.4064)
			(stroke
				(width 0.1524)
				(type default)
			)
			(layer "F.SilkS")
		)
		(fp_line
			(start -0.67945 -0.305054)
			(end -0.12065 -0.305054)
			(stroke
				(width 0.1)
				(type default)
			)
			(layer "F.Fab")
		)
		(fp_line
			(start -0.67945 0.3048)
			(end -0.67945 -0.305054)
			(stroke
				(width 0.1)
				(type default)
			)
			(layer "F.Fab")
		)
		(fp_line
			(start -0.12065 -0.305054)
			(end -0.12065 -0.2794)
			(stroke
				(width 0.1)
				(type default)
			)
			(layer "F.Fab")
		)
		(fp_line
			(start -0.12065 -0.2794)
			(end 0.12065 -0.2794)
			(stroke
				(width 0.1)
				(type default)
			)
			(layer "F.Fab")
		)
		(fp_line
			(start -0.12065 0.2794)
			(end -0.12065 0.3048)
			(stroke
				(width 0.1)
				(type default)
			)
			(layer "F.Fab")
		)
		(fp_line
			(start -0.12065 0.3048)
			(end -0.67945 0.3048)
			(stroke
				(width 0.1)
				(type default)
			)
			(layer "F.Fab")
		)
		(fp_line
			(start 0.120396 0.2794)
			(end -0.12065 0.2794)
			(stroke
				(width 0.1)
				(type default)
			)
			(layer "F.Fab")
		)
		(fp_line
			(start 0.120396 0.3048)
			(end 0.120396 0.2794)
			(stroke
				(width 0.1)
				(type default)
			)
			(layer "F.Fab")
		)
		(fp_line
			(start 0.12065 -0.3048)
			(end 0.67945 -0.3048)
			(stroke
				(width 0.1)
				(type default)
			)
			(layer "F.Fab")
		)
		(fp_line
			(start 0.12065 -0.2794)
			(end 0.12065 -0.3048)
			(stroke
				(width 0.1)
				(type default)
			)
			(layer "F.Fab")
		)
		(fp_line
			(start 0.67945 -0.3048)
			(end 0.67945 0.3048)
			(stroke
				(width 0.1)
				(type default)
			)
			(layer "F.Fab")
		)
		(fp_line
			(start 0.67945 0.3048)
			(end 0.120396 0.3048)
			(stroke
				(width 0.1)
				(type default)
			)
			(layer "F.Fab")
		)
		(pad "1" smd circle
			(at -0.40005 0)
			(size 0 0)
			(layers "F.Cu" "F.Mask" "F.Paste")
			(net "RST_SMB_SSD10_ISO_N")
		)
		(pad "2" smd circle
			(at 0.40005 0)
			(size 0 0)
			(layers "F.Cu" "F.Mask" "F.Paste")
			(net "GND")
		)
	)
	(footprint ""
		(layer "F.Cu")
		(at 378.382022 -289.790632 180)
		(property "Reference" "C3571"
			(at 0 0 180)
			(layer "F.SilkS")
			(hide yes)
			(effects
				(font
					(size 1.27 1.27)
				)
			)
		)
		(property "Value" ""
			(at 0 0 180)
			(layer "F.Fab")
			(effects
				(font
					(size 1.27 1.27)
				)
			)
		)
		(duplicate_pad_numbers_are_jumpers no)
		(fp_line
			(start 1.2954 0.5842)
			(end -1.2954 0.5842)
			(stroke
				(width 0.1524)
				(type default)
			)
			(layer "F.SilkS")
		)
		(fp_line
			(start 1.2954 -0.5842)
			(end 1.2954 0.5842)
			(stroke
				(width 0.1524)
				(type default)
			)
			(layer "F.SilkS")
		)
		(fp_line
			(start -1.2954 0.5842)
			(end -1.2954 -0.5842)
			(stroke
				(width 0.1524)
				(type default)
			)
			(layer "F.SilkS")
		)
		(fp_line
			(start -1.2954 -0.5842)
			(end 1.2954 -0.5842)
			(stroke
				(width 0.1524)
				(type default)
			)
			(layer "F.SilkS")
		)
		(fp_line
			(start 1.1938 0.4064)
			(end 0.8636 0.4064)
			(stroke
				(width 0.1)
				(type default)
			)
			(layer "F.Fab")
		)
		(fp_line
			(start 1.1938 -0.4064)
			(end 1.1938 0.4064)
			(stroke
				(width 0.1)
				(type default)
			)
			(layer "F.Fab")
		)
		(fp_line
			(start 0.8636 0.4572)
			(end -0.8636 0.4572)
			(stroke
				(width 0.1)
				(type default)
			)
			(layer "F.Fab")
		)
		(fp_line
			(start 0.8636 0.4064)
			(end 0.8636 0.4572)
			(stroke
				(width 0.1)
				(type default)
			)
			(layer "F.Fab")
		)
		(fp_line
			(start 0.8636 -0.4064)
			(end 1.1938 -0.4064)
			(stroke
				(width 0.1)
				(type default)
			)
			(layer "F.Fab")
		)
		(fp_line
			(start 0.8636 -0.4572)
			(end 0.8636 -0.4064)
			(stroke
				(width 0.1)
				(type default)
			)
			(layer "F.Fab")
		)
		(fp_line
			(start -0.8636 0.4572)
			(end -0.8636 0.4064)
			(stroke
				(width 0.1)
				(type default)
			)
			(layer "F.Fab")
		)
		(fp_line
			(start -0.8636 0.4064)
			(end -1.1938 0.4064)
			(stroke
				(width 0.1)
				(type default)
			)
			(layer "F.Fab")
		)
		(fp_line
			(start -0.8636 -0.4064)
			(end -0.8636 -0.4572)
			(stroke
				(width 0.1)
				(type default)
			)
			(layer "F.Fab")
		)
		(fp_line
			(start -0.8636 -0.4572)
			(end 0.8636 -0.4572)
			(stroke
				(width 0.1)
				(type default)
			)
			(layer "F.Fab")
		)
		(fp_line
			(start -1.1938 0.4064)
			(end -1.1938 -0.4064)
			(stroke
				(width 0.1)
				(type default)
			)
			(layer "F.Fab")
		)
		(fp_line
			(start -1.1938 -0.4064)
			(end -0.8636 -0.4064)
			(stroke
				(width 0.1)
				(type default)
			)
			(layer "F.Fab")
		)
		(pad "1" smd rect
			(at -0.7366 0 90)
			(size 0.7112 0.8128)
			(layers "F.Cu" "F.Mask" "F.Paste")
			(net "PCEPLL4_VDDA18_PEX3_R")
		)
		(pad "2" smd rect
			(at 0.7366 0 90)
			(size 0.7112 0.8128)
			(layers "F.Cu" "F.Mask" "F.Paste")
			(net "GND")
		)
	)
	(footprint ""
		(layer "F.Cu")
		(at 331.147166 -19.33956)
		(property "Reference" "C3954"
			(at 0 0 0)
			(layer "F.SilkS")
			(hide yes)
			(effects
				(font
					(size 1.27 1.27)
				)
			)
		)
		(property "Value" ""
			(at 0 0 0)
			(layer "F.Fab")
			(effects
				(font
					(size 1.27 1.27)
				)
			)
		)
		(duplicate_pad_numbers_are_jumpers no)
		(fp_line
			(start -0.7874 -0.4064)
			(end 0.7874 -0.4064)
			(stroke
				(width 0.1524)
				(type default)
			)
			(layer "F.SilkS")
		)
		(fp_line
			(start -0.7874 0.4064)
			(end -0.7874 -0.4064)
			(stroke
				(width 0.1524)
				(type default)
			)
			(layer "F.SilkS")
		)
		(fp_line
			(start 0.7874 -0.4064)
			(end 0.7874 0.4064)
			(stroke
				(width 0.1524)
				(type default)
			)
			(layer "F.SilkS")
		)
		(fp_line
			(start 0.7874 0.4064)
			(end -0.7874 0.4064)
			(stroke
				(width 0.1524)
				(type default)
			)
			(layer "F.SilkS")
		)
		(fp_line
			(start -0.67945 -0.305054)
			(end -0.12065 -0.305054)
			(stroke
				(width 0.1)
				(type default)
			)
			(layer "F.Fab")
		)
		(fp_line
			(start -0.67945 0.3048)
			(end -0.67945 -0.305054)
			(stroke
				(width 0.1)
				(type default)
			)
			(layer "F.Fab")
		)
		(fp_line
			(start -0.12065 -0.305054)
			(end -0.12065 -0.2794)
			(stroke
				(width 0.1)
				(type default)
			)
			(layer "F.Fab")
		)
		(fp_line
			(start -0.12065 -0.2794)
			(end 0.12065 -0.2794)
			(stroke
				(width 0.1)
				(type default)
			)
			(layer "F.Fab")
		)
		(fp_line
			(start -0.12065 0.2794)
			(end -0.12065 0.3048)
			(stroke
				(width 0.1)
				(type default)
			)
			(layer "F.Fab")
		)
		(fp_line
			(start -0.12065 0.3048)
			(end -0.67945 0.3048)
			(stroke
				(width 0.1)
				(type default)
			)
			(layer "F.Fab")
		)
		(fp_line
			(start 0.120396 0.2794)
			(end -0.12065 0.2794)
			(stroke
				(width 0.1)
				(type default)
			)
			(layer "F.Fab")
		)
		(fp_line
			(start 0.120396 0.3048)
			(end 0.120396 0.2794)
			(stroke
				(width 0.1)
				(type default)
			)
			(layer "F.Fab")
		)
		(fp_line
			(start 0.12065 -0.3048)
			(end 0.67945 -0.3048)
			(stroke
				(width 0.1)
				(type default)
			)
			(layer "F.Fab")
		)
		(fp_line
			(start 0.12065 -0.2794)
			(end 0.12065 -0.3048)
			(stroke
				(width 0.1)
				(type default)
			)
			(layer "F.Fab")
		)
		(fp_line
			(start 0.67945 -0.3048)
			(end 0.67945 0.3048)
			(stroke
				(width 0.1)
				(type default)
			)
			(layer "F.Fab")
		)
		(fp_line
			(start 0.67945 0.3048)
			(end 0.120396 0.3048)
			(stroke
				(width 0.1)
				(type default)
			)
			(layer "F.Fab")
		)
		(pad "1" smd circle
			(at -0.40005 0)
			(size 0 0)
			(layers "F.Cu" "F.Mask" "F.Paste")
			(net "P12V_SSD11")
		)
		(pad "2" smd circle
			(at 0.40005 0)
			(size 0 0)
			(layers "F.Cu" "F.Mask" "F.Paste")
			(net "GND")
		)
	)
)
